(kicad_pcb
	(version 20221018)
	(generator pcbnew)
	(general
    (thickness 1.62)
  )
	(paper "A4")
	(title_block
    (title "ECP5 - Datacenter Secure Control Module (DC-SCM)")
    (date "2024-07-01")
    (rev "1.2.1")
		(comment 9 "footprints 247-254 of 506")
	)
	(layers
    (0 "F.Cu" signal)
    (1 "In1.Cu" power)
    (2 "In2.Cu" signal)
    (3 "In3.Cu" power)
    (4 "In4.Cu" power)
    (5 "In5.Cu" signal)
    (6 "In6.Cu" power)
    (31 "B.Cu" signal)
    (32 "B.Adhes" user "B.Adhesive")
    (33 "F.Adhes" user "F.Adhesive")
    (34 "B.Paste" user)
    (35 "F.Paste" user)
    (36 "B.SilkS" user "B.Silkscreen")
    (37 "F.SilkS" user "F.Silkscreen")
    (38 "B.Mask" user)
    (39 "F.Mask" user)
    (40 "Dwgs.User" user "User.Drawings")
    (41 "Cmts.User" user "User.Comments")
    (42 "Eco1.User" user "User.Eco1")
    (43 "Eco2.User" user "User.Eco2")
    (44 "Edge.Cuts" user)
    (45 "Margin" user)
    (46 "B.CrtYd" user "B.Courtyard")
    (47 "F.CrtYd" user "F.Courtyard")
    (48 "B.Fab" user)
    (49 "F.Fab" user)
  )
	(footprint "antmicro-footprints:C_0402_1005Metric" (layer "B.Cu")
    (at 128.625 118.55)
    (descr "Capacitor SMD 0402")
    (tags "capacitor SMD 0402")
    (property "Author" "Antmicro")
    (property "Dielectric" "X5R")
    (property "License" "Apache-2.0")
    (property "MPN" "GRM155R61H104KE14D")
    (property "Manufacturer" "Murata")
    (property "Public" "False")
    (property "Sheetfile" "interfaces.kicad_sch")
    (property "Sheetname" "Interfaces")
    (property "Val" "100n")
    (property "Voltage" "50V")
    (property "ki_description" "SMD Multilayer Ceramic Capacitor, 0.1 µF, 50 V, 0402 [1005 Metric], ± 10%, X5R, GRM Series")
    (property "ki_keywords" "0402, SMT, CAPACITOR, PASSIVE, CERAMIC, MLCC")
    (attr smd)
    (fp_text reference "C67" (at -3.025 -0.025) (layer "B.SilkS")
        (effects (font (size 0.7 0.7) (thickness 0.127)) (justify mirror))
    )
    (fp_text value "C_100n_0402" (at 0 -1.17) (layer "B.Fab")
        (effects (font (size 1 1) (thickness 0.15)) (justify mirror))
    )
    (fp_text user "Author: Antmicro" (at -0.939 -3.399 180) (layer "B.Fab") hide
        (effects (font (size 0.7 0.7) (thickness 0.15)) (justify left bottom mirror))
    )
    (fp_text user "License: Apache-2.0" (at -0.939 -5.799 180) (layer "B.Fab") hide
        (effects (font (size 0.7 0.7) (thickness 0.15)) (justify left bottom mirror))
    )
    (fp_text user "${REFERENCE}" (at 0 0) (layer "B.Fab")
        (effects (font (size 0.25 0.25) (thickness 0.04)) (justify mirror))
    )
    (fp_rect (start -0.925 0.47) (end 0.925 -0.47)
      (stroke (width 0.05) (type default)) (fill none) (layer "B.CrtYd"))
    (fp_line (start -0.494 -0.248) (end -0.494 0.25)
      (stroke (width 0.15) (type solid)) (layer "B.Fab"))
    (fp_line (start -0.494 0.25) (end 0.504 0.25)
      (stroke (width 0.15) (type solid)) (layer "B.Fab"))
    (fp_line (start 0.504 -0.248) (end -0.494 -0.248)
      (stroke (width 0.15) (type solid)) (layer "B.Fab"))
    (fp_line (start 0.504 0.25) (end 0.504 -0.248)
      (stroke (width 0.15) (type solid)) (layer "B.Fab"))
    (pad "1" smd roundrect (at -0.48 0) (size 0.59 0.64) (layers "B.Cu" "B.Paste" "B.Mask") (roundrect_rratio 0.25)
      (net 2 "VCC3V3") (pintype "passive"))
    (pad "2" smd roundrect (at 0.48 0) (size 0.59 0.64) (layers "B.Cu" "B.Paste" "B.Mask") (roundrect_rratio 0.25)
      (net 1 "GND") (pintype "passive"))
  )
	(footprint "antmicro-footprints:C_0402_1005Metric" (layer "B.Cu")
    (at 122.35 118.335 90)
    (descr "Capacitor SMD 0402")
    (tags "capacitor SMD 0402")
    (property "Author" "Antmicro")
    (property "Dielectric" "")
    (property "License" "Apache-2.0")
    (property "MPN" "GRM155R61A475MEAAD")
    (property "Manufacturer" "Murata")
    (property "Public" "False")
    (property "Sheetfile" "interfaces.kicad_sch")
    (property "Sheetname" "Interfaces")
    (property "Val" "4u7")
    (property "Voltage" "")
    (property "ki_description" "SMD Multilayer Ceramic Capacitor, 4.7 µF, 10 V, 0402 [1005 Metric], ± 20%, X5R, GRM Series")
    (property "ki_keywords" "0402, SMT, CAPACITOR, PASSIVE")
    (attr smd)
    (fp_text reference "C72" (at -1.92 0 90) (layer "B.SilkS")
        (effects (font (size 0.7 0.7) (thickness 0.127)) (justify mirror))
    )
    (fp_text value "C_4u7_0402" (at 0 -1.17 90) (layer "B.Fab")
        (effects (font (size 1 1) (thickness 0.15)) (justify mirror))
    )
    (fp_text user "Author: Antmicro" (at -0.939 -3.399 270) (layer "B.Fab") hide
        (effects (font (size 0.7 0.7) (thickness 0.15)) (justify left bottom mirror))
    )
    (fp_text user "${REFERENCE}" (at 0 0 90) (layer "B.Fab")
        (effects (font (size 0.25 0.25) (thickness 0.04)) (justify mirror))
    )
    (fp_text user "License: Apache-2.0" (at -0.939 -5.799 270) (layer "B.Fab") hide
        (effects (font (size 0.7 0.7) (thickness 0.15)) (justify left bottom mirror))
    )
    (fp_rect (start -0.925 0.47) (end 0.925 -0.47)
      (stroke (width 0.05) (type default)) (fill none) (layer "B.CrtYd"))
    (fp_line (start -0.494 -0.248) (end -0.494 0.25)
      (stroke (width 0.15) (type solid)) (layer "B.Fab"))
    (fp_line (start -0.494 0.25) (end 0.504 0.25)
      (stroke (width 0.15) (type solid)) (layer "B.Fab"))
    (fp_line (start 0.504 -0.248) (end -0.494 -0.248)
      (stroke (width 0.15) (type solid)) (layer "B.Fab"))
    (fp_line (start 0.504 0.25) (end 0.504 -0.248)
      (stroke (width 0.15) (type solid)) (layer "B.Fab"))
    (pad "1" smd roundrect (at -0.48 0 90) (size 0.59 0.64) (layers "B.Cu" "B.Paste" "B.Mask") (roundrect_rratio 0.25)
      (net 1 "GND") (pintype "passive"))
    (pad "2" smd roundrect (at 0.48 0 90) (size 0.59 0.64) (layers "B.Cu" "B.Paste" "B.Mask") (roundrect_rratio 0.25)
      (net 2 "VCC3V3") (pintype "passive"))
  )
	(footprint "antmicro-footprints:C_0402_1005Metric" (layer "B.Cu")
    (at 78 124.7 90)
    (descr "Capacitor SMD 0402")
    (tags "capacitor SMD 0402")
    (property "Author" "Antmicro")
    (property "Dielectric" "")
    (property "License" "Apache-2.0")
    (property "MPN" "GRM155R61A475MEAAD")
    (property "Manufacturer" "Murata")
    (property "Public" "False")
    (property "Sheetfile" "ddr3.kicad_sch")
    (property "Sheetname" "DDR3")
    (property "Val" "4u7")
    (property "Voltage" "")
    (property "ki_description" "SMD Multilayer Ceramic Capacitor, 4.7 µF, 10 V, 0402 [1005 Metric], ± 20%, X5R, GRM Series")
    (property "ki_keywords" "0402, SMT, CAPACITOR, PASSIVE")
    (attr smd)
    (fp_text reference "C79" (at 0.005 -2.5 90) (layer "B.SilkS")
        (effects (font (size 0.7 0.7) (thickness 0.127)) (justify mirror))
    )
    (fp_text value "C_4u7_0402" (at 0 -1.17 90) (layer "B.Fab")
        (effects (font (size 1 1) (thickness 0.15)) (justify mirror))
    )
    (fp_text user "${REFERENCE}" (at 0 0 90) (layer "B.Fab")
        (effects (font (size 0.25 0.25) (thickness 0.04)) (justify mirror))
    )
    (fp_text user "Author: Antmicro" (at -0.939 -3.399 270) (layer "B.Fab") hide
        (effects (font (size 0.7 0.7) (thickness 0.15)) (justify left bottom mirror))
    )
    (fp_text user "License: Apache-2.0" (at -0.939 -5.799 270) (layer "B.Fab") hide
        (effects (font (size 0.7 0.7) (thickness 0.15)) (justify left bottom mirror))
    )
    (fp_rect (start -0.925 0.47) (end 0.925 -0.47)
      (stroke (width 0.05) (type default)) (fill none) (layer "B.CrtYd"))
    (fp_line (start -0.494 -0.248) (end -0.494 0.25)
      (stroke (width 0.15) (type solid)) (layer "B.Fab"))
    (fp_line (start -0.494 0.25) (end 0.504 0.25)
      (stroke (width 0.15) (type solid)) (layer "B.Fab"))
    (fp_line (start 0.504 -0.248) (end -0.494 -0.248)
      (stroke (width 0.15) (type solid)) (layer "B.Fab"))
    (fp_line (start 0.504 0.25) (end 0.504 -0.248)
      (stroke (width 0.15) (type solid)) (layer "B.Fab"))
    (pad "1" smd roundrect (at -0.48 0 90) (size 0.59 0.64) (layers "B.Cu" "B.Paste" "B.Mask") (roundrect_rratio 0.25)
      (net 1 "GND") (pintype "passive"))
    (pad "2" smd roundrect (at 0.48 0 90) (size 0.59 0.64) (layers "B.Cu" "B.Paste" "B.Mask") (roundrect_rratio 0.25)
      (net 3 "VCC1V35") (pintype "passive"))
  )
	(footprint "antmicro-footprints:C_0402_1005Metric" (layer "B.Cu")
    (at 85.9 129.75)
    (descr "Capacitor SMD 0402")
    (tags "capacitor SMD 0402")
    (property "Author" "Antmicro")
    (property "Dielectric" "")
    (property "License" "Apache-2.0")
    (property "MPN" "C1005X5R1E474M050BB")
    (property "Manufacturer" "TDK")
    (property "Public" "False")
    (property "Sheetfile" "ddr3.kicad_sch")
    (property "Sheetname" "DDR3")
    (property "Val" "470n")
    (property "Voltage" "")
    (property "ki_description" "SMD Multilayer Ceramic Capacitor, 0.47 µF, 25 V, 0402 [1005 Metric], ± 20%, X5R, C")
    (property "ki_keywords" "0402, SMT, CAPACITOR, PASSIVE, CERAMIC, MLCC")
    (attr smd)
    (fp_text reference "C80" (at -0.03 1.425) (layer "B.SilkS")
        (effects (font (size 0.7 0.7) (thickness 0.127)) (justify mirror))
    )
    (fp_text value "C_470n_0402" (at 0 -1.17) (layer "B.Fab")
        (effects (font (size 1 1) (thickness 0.15)) (justify mirror))
    )
    (fp_text user "License: Apache-2.0" (at -0.939 -5.799 180) (layer "B.Fab") hide
        (effects (font (size 0.7 0.7) (thickness 0.15)) (justify left bottom mirror))
    )
    (fp_text user "${REFERENCE}" (at 0 0) (layer "B.Fab")
        (effects (font (size 0.25 0.25) (thickness 0.04)) (justify mirror))
    )
    (fp_text user "Author: Antmicro" (at -0.939 -3.399 180) (layer "B.Fab") hide
        (effects (font (size 0.7 0.7) (thickness 0.15)) (justify left bottom mirror))
    )
    (fp_rect (start -0.925 0.47) (end 0.925 -0.47)
      (stroke (width 0.05) (type default)) (fill none) (layer "B.CrtYd"))
    (fp_line (start -0.494 -0.248) (end -0.494 0.25)
      (stroke (width 0.15) (type solid)) (layer "B.Fab"))
    (fp_line (start -0.494 0.25) (end 0.504 0.25)
      (stroke (width 0.15) (type solid)) (layer "B.Fab"))
    (fp_line (start 0.504 -0.248) (end -0.494 -0.248)
      (stroke (width 0.15) (type solid)) (layer "B.Fab"))
    (fp_line (start 0.504 0.25) (end 0.504 -0.248)
      (stroke (width 0.15) (type solid)) (layer "B.Fab"))
    (pad "1" smd roundrect (at -0.48 0) (size 0.59 0.64) (layers "B.Cu" "B.Paste" "B.Mask") (roundrect_rratio 0.25)
      (net 1 "GND") (pintype "passive"))
    (pad "2" smd roundrect (at 0.48 0) (size 0.59 0.64) (layers "B.Cu" "B.Paste" "B.Mask") (roundrect_rratio 0.25)
      (net 3 "VCC1V35") (pintype "passive"))
  )
	(footprint "antmicro-footprints:C_0402_1005Metric" (layer "B.Cu")
    (at 79.05 126.75 -90)
    (descr "Capacitor SMD 0402")
    (tags "capacitor SMD 0402")
    (property "Author" "Antmicro")
    (property "Dielectric" "")
    (property "License" "Apache-2.0")
    (property "MPN" "C1005X5R1E474M050BB")
    (property "Manufacturer" "TDK")
    (property "Public" "False")
    (property "Sheetfile" "ddr3.kicad_sch")
    (property "Sheetname" "DDR3")
    (property "Val" "470n")
    (property "Voltage" "")
    (property "ki_description" "SMD Multilayer Ceramic Capacitor, 0.47 µF, 25 V, 0402 [1005 Metric], ± 20%, X5R, C")
    (property "ki_keywords" "0402, SMT, CAPACITOR, PASSIVE, CERAMIC, MLCC")
    (attr smd)
    (fp_text reference "C81" (at 0.445 0.83 90) (layer "B.SilkS")
        (effects (font (size 0.7 0.7) (thickness 0.127)) (justify mirror))
    )
    (fp_text value "C_470n_0402" (at 0 -1.17 90) (layer "B.Fab")
        (effects (font (size 1 1) (thickness 0.15)) (justify mirror))
    )
    (fp_text user "${REFERENCE}" (at 0 0 90) (layer "B.Fab")
        (effects (font (size 0.25 0.25) (thickness 0.04)) (justify mirror))
    )
    (fp_text user "Author: Antmicro" (at -0.939 -3.399 90) (layer "B.Fab") hide
        (effects (font (size 0.7 0.7) (thickness 0.15)) (justify left bottom mirror))
    )
    (fp_text user "License: Apache-2.0" (at -0.939 -5.799 90) (layer "B.Fab") hide
        (effects (font (size 0.7 0.7) (thickness 0.15)) (justify left bottom mirror))
    )
    (fp_rect (start -0.925 0.47) (end 0.925 -0.47)
      (stroke (width 0.05) (type default)) (fill none) (layer "B.CrtYd"))
    (fp_line (start -0.494 -0.248) (end -0.494 0.25)
      (stroke (width 0.15) (type solid)) (layer "B.Fab"))
    (fp_line (start -0.494 0.25) (end 0.504 0.25)
      (stroke (width 0.15) (type solid)) (layer "B.Fab"))
    (fp_line (start 0.504 -0.248) (end -0.494 -0.248)
      (stroke (width 0.15) (type solid)) (layer "B.Fab"))
    (fp_line (start 0.504 0.25) (end 0.504 -0.248)
      (stroke (width 0.15) (type solid)) (layer "B.Fab"))
    (pad "1" smd roundrect (at -0.48 0 270) (size 0.59 0.64) (layers "B.Cu" "B.Paste" "B.Mask") (roundrect_rratio 0.25)
      (net 1 "GND") (pintype "passive"))
    (pad "2" smd roundrect (at 0.48 0 270) (size 0.59 0.64) (layers "B.Cu" "B.Paste" "B.Mask") (roundrect_rratio 0.25)
      (net 3 "VCC1V35") (pintype "passive"))
  )
	(footprint "antmicro-footprints:C_0402_1005Metric" (layer "B.Cu")
    (at 79.04 128.72 90)
    (descr "Capacitor SMD 0402")
    (tags "capacitor SMD 0402")
    (property "Author" "Antmicro")
    (property "Dielectric" "")
    (property "License" "Apache-2.0")
    (property "MPN" "C1005X5R1E474M050BB")
    (property "Manufacturer" "TDK")
    (property "Public" "False")
    (property "Sheetfile" "ddr3.kicad_sch")
    (property "Sheetname" "DDR3")
    (property "Val" "470n")
    (property "Voltage" "")
    (property "ki_description" "SMD Multilayer Ceramic Capacitor, 0.47 µF, 25 V, 0402 [1005 Metric], ± 20%, X5R, C")
    (property "ki_keywords" "0402, SMT, CAPACITOR, PASSIVE, CERAMIC, MLCC")
    (attr smd)
    (fp_text reference "C82" (at -0.745 -0.89 90) (layer "B.SilkS")
        (effects (font (size 0.7 0.7) (thickness 0.127)) (justify mirror))
    )
    (fp_text value "C_470n_0402" (at 0 -1.17 90) (layer "B.Fab")
        (effects (font (size 1 1) (thickness 0.15)) (justify mirror))
    )
    (fp_text user "Author: Antmicro" (at -0.939 -3.399 270) (layer "B.Fab") hide
        (effects (font (size 0.7 0.7) (thickness 0.15)) (justify left bottom mirror))
    )
    (fp_text user "License: Apache-2.0" (at -0.939 -5.799 270) (layer "B.Fab") hide
        (effects (font (size 0.7 0.7) (thickness 0.15)) (justify left bottom mirror))
    )
    (fp_text user "${REFERENCE}" (at 0 0 90) (layer "B.Fab")
        (effects (font (size 0.25 0.25) (thickness 0.04)) (justify mirror))
    )
    (fp_rect (start -0.925 0.47) (end 0.925 -0.47)
      (stroke (width 0.05) (type default)) (fill none) (layer "B.CrtYd"))
    (fp_line (start -0.494 -0.248) (end -0.494 0.25)
      (stroke (width 0.15) (type solid)) (layer "B.Fab"))
    (fp_line (start -0.494 0.25) (end 0.504 0.25)
      (stroke (width 0.15) (type solid)) (layer "B.Fab"))
    (fp_line (start 0.504 -0.248) (end -0.494 -0.248)
      (stroke (width 0.15) (type solid)) (layer "B.Fab"))
    (fp_line (start 0.504 0.25) (end 0.504 -0.248)
      (stroke (width 0.15) (type solid)) (layer "B.Fab"))
    (pad "1" smd roundrect (at -0.48 0 90) (size 0.59 0.64) (layers "B.Cu" "B.Paste" "B.Mask") (roundrect_rratio 0.25)
      (net 1 "GND") (pintype "passive"))
    (pad "2" smd roundrect (at 0.48 0 90) (size 0.59 0.64) (layers "B.Cu" "B.Paste" "B.Mask") (roundrect_rratio 0.25)
      (net 3 "VCC1V35") (pintype "passive"))
  )
	(footprint "antmicro-footprints:C_0402_1005Metric" (layer "B.Cu")
    (at 85.9 128.25)
    (descr "Capacitor SMD 0402")
    (tags "capacitor SMD 0402")
    (property "Author" "Antmicro")
    (property "Dielectric" "")
    (property "License" "Apache-2.0")
    (property "MPN" "C1005X5R1E474M050BB")
    (property "Manufacturer" "TDK")
    (property "Public" "False")
    (property "Sheetfile" "ddr3.kicad_sch")
    (property "Sheetname" "DDR3")
    (property "Val" "470n")
    (property "Voltage" "")
    (property "ki_description" "SMD Multilayer Ceramic Capacitor, 0.47 µF, 25 V, 0402 [1005 Metric], ± 20%, X5R, C")
    (property "ki_keywords" "0402, SMT, CAPACITOR, PASSIVE, CERAMIC, MLCC")
    (attr smd)
    (fp_text reference "C83" (at 2.43 -0.045) (layer "B.SilkS")
        (effects (font (size 0.7 0.7) (thickness 0.127)) (justify mirror))
    )
    (fp_text value "C_470n_0402" (at 0 -1.17) (layer "B.Fab")
        (effects (font (size 1 1) (thickness 0.15)) (justify mirror))
    )
    (fp_text user "Author: Antmicro" (at -0.939 -3.399 180) (layer "B.Fab") hide
        (effects (font (size 0.7 0.7) (thickness 0.15)) (justify left bottom mirror))
    )
    (fp_text user "${REFERENCE}" (at 0 0) (layer "B.Fab")
        (effects (font (size 0.25 0.25) (thickness 0.04)) (justify mirror))
    )
    (fp_text user "License: Apache-2.0" (at -0.939 -5.799 180) (layer "B.Fab") hide
        (effects (font (size 0.7 0.7) (thickness 0.15)) (justify left bottom mirror))
    )
    (fp_rect (start -0.925 0.47) (end 0.925 -0.47)
      (stroke (width 0.05) (type default)) (fill none) (layer "B.CrtYd"))
    (fp_line (start -0.494 -0.248) (end -0.494 0.25)
      (stroke (width 0.15) (type solid)) (layer "B.Fab"))
    (fp_line (start -0.494 0.25) (end 0.504 0.25)
      (stroke (width 0.15) (type solid)) (layer "B.Fab"))
    (fp_line (start 0.504 -0.248) (end -0.494 -0.248)
      (stroke (width 0.15) (type solid)) (layer "B.Fab"))
    (fp_line (start 0.504 0.25) (end 0.504 -0.248)
      (stroke (width 0.15) (type solid)) (layer "B.Fab"))
    (pad "1" smd roundrect (at -0.48 0) (size 0.59 0.64) (layers "B.Cu" "B.Paste" "B.Mask") (roundrect_rratio 0.25)
      (net 1 "GND") (pintype "passive"))
    (pad "2" smd roundrect (at 0.48 0) (size 0.59 0.64) (layers "B.Cu" "B.Paste" "B.Mask") (roundrect_rratio 0.25)
      (net 3 "VCC1V35") (pintype "passive"))
  )
	(footprint "antmicro-footprints:C_0402_1005Metric" (layer "B.Cu")
    (at 87.85 127.25)
    (descr "Capacitor SMD 0402")
    (tags "capacitor SMD 0402")
    (property "Author" "Antmicro")
    (property "Dielectric" "")
    (property "License" "Apache-2.0")
    (property "MPN" "C1005X5R1E474M050BB")
    (property "Manufacturer" "TDK")
    (property "Public" "False")
    (property "Sheetfile" "ddr3.kicad_sch")
    (property "Sheetname" "DDR3")
    (property "Val" "470n")
    (property "Voltage" "")
    (property "ki_description" "SMD Multilayer Ceramic Capacitor, 0.47 µF, 25 V, 0402 [1005 Metric], ± 20%, X5R, C")
    (property "ki_keywords" "0402, SMT, CAPACITOR, PASSIVE, CERAMIC, MLCC")
    (attr smd)
    (fp_text reference "C84" (at 1.98 -0.025) (layer "B.SilkS")
        (effects (font (size 0.7 0.7) (thickness 0.127)) (justify mirror))
    )
    (fp_text value "C_470n_0402" (at 0 -1.17) (layer "B.Fab")
        (effects (font (size 1 1) (thickness 0.15)) (justify mirror))
    )
    (fp_text user "${REFERENCE}" (at 0 0) (layer "B.Fab")
        (effects (font (size 0.25 0.25) (thickness 0.04)) (justify mirror))
    )
    (fp_text user "Author: Antmicro" (at -0.939 -3.399 180) (layer "B.Fab") hide
        (effects (font (size 0.7 0.7) (thickness 0.15)) (justify left bottom mirror))
    )
    (fp_text user "License: Apache-2.0" (at -0.939 -5.799 180) (layer "B.Fab") hide
        (effects (font (size 0.7 0.7) (thickness 0.15)) (justify left bottom mirror))
    )
    (fp_rect (start -0.925 0.47) (end 0.925 -0.47)
      (stroke (width 0.05) (type default)) (fill none) (layer "B.CrtYd"))
    (fp_line (start -0.494 -0.248) (end -0.494 0.25)
      (stroke (width 0.15) (type solid)) (layer "B.Fab"))
    (fp_line (start -0.494 0.25) (end 0.504 0.25)
      (stroke (width 0.15) (type solid)) (layer "B.Fab"))
    (fp_line (start 0.504 -0.248) (end -0.494 -0.248)
      (stroke (width 0.15) (type solid)) (layer "B.Fab"))
    (fp_line (start 0.504 0.25) (end 0.504 -0.248)
      (stroke (width 0.15) (type solid)) (layer "B.Fab"))
    (pad "1" smd roundrect (at -0.48 0) (size 0.59 0.64) (layers "B.Cu" "B.Paste" "B.Mask") (roundrect_rratio 0.25)
      (net 1 "GND") (pintype "passive"))
    (pad "2" smd roundrect (at 0.48 0) (size 0.59 0.64) (layers "B.Cu" "B.Paste" "B.Mask") (roundrect_rratio 0.25)
      (net 3 "VCC1V35") (pintype "passive"))
  )
)
